# S9S_MB_2U (Grand Teton) — schematic netlist excerpt (pin names and nets, part order shuffled) for the footprints in the layout excerpt that follows; sources: Cadence DE-HDL packaged netlist, KiCad conversion of 03242023_DA0F0TMBIJ0_F0T_Motherboard_J_brd_V01_OCP.brd

R1232  Q_RES  240 1% EMPTY  pkg 0402LF  page 119 : A = PVNN_TERM_CPU0 ; B = PUD_XTAL_CPU0_MODE0
R4496  Q_RES  33.2 1% CHIP  pkg 0402LF  page 237 : A = SMB_HOST_CLK_BUF_ISO_3V3AUX_SCL ; B = SMB_HOST_DB2000_3V3AUX_SCL

(kicad_pcb
	(version 20260206)
	(generator "pcbnew")
	(generator_version "10.0")
	(general
		(thickness 1.6)
		(legacy_teardrops no)
	)
	(paper "A4")
	(title_block
		(title "03242023_DA0F0TMBIJ0_F0T_Motherboard_J_brd_V01_OCP.brd")
		(comment 1 "Grand Teton / footprints 2796-2797 of 6105")
	)
	(layers
		(0 "F.Cu" signal "TOP")
		(4 "In1.Cu" signal "GND")
		(6 "In2.Cu" signal "IN1")
		(8 "In3.Cu" signal "GND1")
		(10 "In4.Cu" signal "IN2")
		(12 "In5.Cu" signal "GND2")
		(14 "In6.Cu" signal "IN3")
		(16 "In7.Cu" signal "GND3")
		(18 "In8.Cu" signal "VCC")
		(20 "In9.Cu" signal "VCC1")
		(22 "In10.Cu" signal "GND4")
		(24 "In11.Cu" signal "IN4")
		(26 "In12.Cu" signal "GND5")
		(28 "In13.Cu" signal "IN5")
		(30 "In14.Cu" signal "GND6")
		(32 "In15.Cu" signal "IN6")
		(34 "In16.Cu" signal "GND7")
		(2 "B.Cu" signal "BOTTOM")
		(9 "F.Adhes" user "F.Adhesive")
		(11 "B.Adhes" user "B.Adhesive")
		(13 "F.Paste" user "Package Geometry/Pastemask Top")
		(15 "B.Paste" user "Package Geometry/Pastemask Bottom")
		(5 "F.SilkS" user "Ref Des/Silkscreen Top")
		(7 "B.SilkS" user "Ref Des/Silkscreen Bottom")
		(1 "F.Mask" user "Board Geometry/Soldermask Top")
		(3 "B.Mask" user "Board Geometry/Soldermask Bottom")
		(17 "Dwgs.User" user "User.Drawings")
		(19 "Cmts.User" user "User.Comments")
		(21 "Eco1.User" user "User.Eco1")
		(23 "Eco2.User" user "User.Eco2")
		(25 "Edge.Cuts" user "Board Geometry/Outline")
		(27 "Margin" user)
		(31 "F.CrtYd" user "Package Geometry/Place Bound Top")
		(29 "B.CrtYd" user "Package Geometry/Place Bound Bottom")
		(35 "F.Fab" user "Ref Des/Assembly Top")
		(33 "B.Fab" user "Ref Des/Assembly Bottom")
	)
	(footprint ""
		(layer "F.Cu")
		(at 406.124664 -359.579926 180)
		(property "Reference" "R1232"
			(at 0 0 180)
			(layer "F.SilkS")
			(hide yes)
			(effects
				(font
					(size 1.27 1.27)
				)
			)
		)
		(property "Value" ""
			(at 0 0 180)
			(layer "F.Fab")
			(effects
				(font
					(size 1.27 1.27)
				)
			)
		)
		(duplicate_pad_numbers_are_jumpers no)
		(fp_line
			(start 0.7874 0.4064)
			(end -0.7874 0.4064)
			(stroke
				(width 0.1524)
				(type default)
			)
			(layer "F.SilkS")
		)
		(fp_line
			(start 0.7874 -0.4064)
			(end 0.7874 0.4064)
			(stroke
				(width 0.1524)
				(type default)
			)
			(layer "F.SilkS")
		)
		(fp_line
			(start -0.7874 0.4064)
			(end -0.7874 -0.4064)
			(stroke
				(width 0.1524)
				(type default)
			)
			(layer "F.SilkS")
		)
		(fp_line
			(start -0.7874 -0.4064)
			(end 0.7874 -0.4064)
			(stroke
				(width 0.1524)
				(type default)
			)
			(layer "F.SilkS")
		)
		(fp_line
			(start 0.67945 0.3048)
			(end 0.120396 0.3048)
			(stroke
				(width 0.1)
				(type default)
			)
			(layer "F.Fab")
		)
		(fp_line
			(start 0.67945 -0.3048)
			(end 0.67945 0.3048)
			(stroke
				(width 0.1)
				(type default)
			)
			(layer "F.Fab")
		)
		(fp_line
			(start 0.12065 -0.2794)
			(end 0.12065 -0.3048)
			(stroke
				(width 0.1)
				(type default)
			)
			(layer "F.Fab")
		)
		(fp_line
			(start 0.12065 -0.3048)
			(end 0.67945 -0.3048)
			(stroke
				(width 0.1)
				(type default)
			)
			(layer "F.Fab")
		)
		(fp_line
			(start 0.120396 0.3048)
			(end 0.120396 0.2794)
			(stroke
				(width 0.1)
				(type default)
			)
			(layer "F.Fab")
		)
		(fp_line
			(start 0.120396 0.2794)
			(end -0.12065 0.2794)
			(stroke
				(width 0.1)
				(type default)
			)
			(layer "F.Fab")
		)
		(fp_line
			(start -0.12065 0.3048)
			(end -0.67945 0.3048)
			(stroke
				(width 0.1)
				(type default)
			)
			(layer "F.Fab")
		)
		(fp_line
			(start -0.12065 0.2794)
			(end -0.12065 0.3048)
			(stroke
				(width 0.1)
				(type default)
			)
			(layer "F.Fab")
		)
		(fp_line
			(start -0.12065 -0.2794)
			(end 0.12065 -0.2794)
			(stroke
				(width 0.1)
				(type default)
			)
			(layer "F.Fab")
		)
		(fp_line
			(start -0.12065 -0.305054)
			(end -0.12065 -0.2794)
			(stroke
				(width 0.1)
				(type default)
			)
			(layer "F.Fab")
		)
		(fp_line
			(start -0.67945 0.3048)
			(end -0.67945 -0.305054)
			(stroke
				(width 0.1)
				(type default)
			)
			(layer "F.Fab")
		)
		(fp_line
			(start -0.67945 -0.305054)
			(end -0.12065 -0.305054)
			(stroke
				(width 0.1)
				(type default)
			)
			(layer "F.Fab")
		)
		(pad "1" smd circle
			(at -0.40005 0 180)
			(size 0 0)
			(layers "F.Cu" "F.Mask" "F.Paste")
			(net "PVNN_TERM_CPU0")
		)
		(pad "2" smd circle
			(at 0.40005 0 180)
			(size 0 0)
			(layers "F.Cu" "F.Mask" "F.Paste")
			(net "PUD_XTAL_CPU0_MODE0")
		)
	)
	(footprint ""
		(layer "F.Cu")
		(at 261.436612 -130.600704 180)
		(property "Reference" "R4496"
			(at 0 0 180)
			(layer "F.SilkS")
			(hide yes)
			(effects
				(font
					(size 1.27 1.27)
				)
			)
		)
		(property "Value" ""
			(at 0 0 180)
			(layer "F.Fab")
			(effects
				(font
					(size 1.27 1.27)
				)
			)
		)
		(duplicate_pad_numbers_are_jumpers no)
		(fp_line
			(start 0.7874 0.4064)
			(end -0.7874 0.4064)
			(stroke
				(width 0.1524)
				(type default)
			)
			(layer "F.SilkS")
		)
		(fp_line
			(start 0.7874 -0.4064)
			(end 0.7874 0.4064)
			(stroke
				(width 0.1524)
				(type default)
			)
			(layer "F.SilkS")
		)
		(fp_line
			(start -0.7874 0.4064)
			(end -0.7874 -0.4064)
			(stroke
				(width 0.1524)
				(type default)
			)
			(layer "F.SilkS")
		)
		(fp_line
			(start -0.7874 -0.4064)
			(end 0.7874 -0.4064)
			(stroke
				(width 0.1524)
				(type default)
			)
			(layer "F.SilkS")
		)
		(fp_line
			(start 0.67945 0.3048)
			(end 0.120396 0.3048)
			(stroke
				(width 0.1)
				(type default)
			)
			(layer "F.Fab")
		)
		(fp_line
			(start 0.67945 -0.3048)
			(end 0.67945 0.3048)
			(stroke
				(width 0.1)
				(type default)
			)
			(layer "F.Fab")
		)
		(fp_line
			(start 0.12065 -0.2794)
			(end 0.12065 -0.3048)
			(stroke
				(width 0.1)
				(type default)
			)
			(layer "F.Fab")
		)
		(fp_line
			(start 0.12065 -0.3048)
			(end 0.67945 -0.3048)
			(stroke
				(width 0.1)
				(type default)
			)
			(layer "F.Fab")
		)
		(fp_line
			(start 0.120396 0.3048)
			(end 0.120396 0.2794)
			(stroke
				(width 0.1)
				(type default)
			)
			(layer "F.Fab")
		)
		(fp_line
			(start 0.120396 0.2794)
			(end -0.12065 0.2794)
			(stroke
				(width 0.1)
				(type default)
			)
			(layer "F.Fab")
		)
		(fp_line
			(start -0.12065 0.3048)
			(end -0.67945 0.3048)
			(stroke
				(width 0.1)
				(type default)
			)
			(layer "F.Fab")
		)
		(fp_line
			(start -0.12065 0.2794)
			(end -0.12065 0.3048)
			(stroke
				(width 0.1)
				(type default)
			)
			(layer "F.Fab")
		)
		(fp_line
			(start -0.12065 -0.2794)
			(end 0.12065 -0.2794)
			(stroke
				(width 0.1)
				(type default)
			)
			(layer "F.Fab")
		)
		(fp_line
			(start -0.12065 -0.305054)
			(end -0.12065 -0.2794)
			(stroke
				(width 0.1)
				(type default)
			)
			(layer "F.Fab")
		)
		(fp_line
			(start -0.67945 0.3048)
			(end -0.67945 -0.305054)
			(stroke
				(width 0.1)
				(type default)
			)
			(layer "F.Fab")
		)
		(fp_line
			(start -0.67945 -0.305054)
			(end -0.12065 -0.305054)
			(stroke
				(width 0.1)
				(type default)
			)
			(layer "F.Fab")
		)
		(pad "1" smd circle
			(at -0.40005 0 180)
			(size 0 0)
			(layers "F.Cu" "F.Mask" "F.Paste")
			(net "SMB_HOST_CLK_BUF_ISO_3V3AUX_SCL")
		)
		(pad "2" smd circle
			(at 0.40005 0 180)
			(size 0 0)
			(layers "F.Cu" "F.Mask" "F.Paste")
			(net "SMB_HOST_DB2000_3V3AUX_SCL")
		)
	)
)
